FILE_TYPE = MULTI_PHYS_TABLE;

PART 'MOSFET_NCH_4D1S'

{========================================================================================}
:VALUE     | PART_TYPE | MATERIAL | PART_NUMBER    = STANDARD | LIFECYCLE      | PART_NUMBER   | JEDEC_TYPE | DESCRIPTION                             | MANUFTR | MANUF_PN  | RD_CMPLS_LVL | CMPLS_LVL | CLASS | DIP_SMD | FP_ECN | FROM_PJ     | DATA              | EE_CHECK_LIST | STATUS | PSL | PREFERENCE | CREATOR | CREATEDAY  ;
{========================================================================================}
 'AO6402A' | 'SMLF'    | 'IC'     | 'BAM64020000'(!) = ''       | ''               | 'BAM64020000' |'TSOP6XD'| 'TRANS MOSFET AO6402A(30V,7A,2W)TSOP-6' | 'AOS'   | 'AO6402A' | 'EP(V1)'     | 'EP(V1)'  | 'IC'  | ''      | ''     | 'T2H-GAVEN' | 'AOS_AO6402A.pdf' | ''            | ''     | ''  | ''         | ''      | '20141008'
 'AO6402A' | 'SMLF'    | 'EMPTY'  | 'BAM64020000'(!) = ''       | ''               | 'BAM64020000' |'TSOP6XD'| 'TRANS MOSFET AO6402A(30V,7A,2W)TSOP-6' | 'AOS'   | 'AO6402A' | 'EP(V1)'     | 'EP(V1)'  | 'IC'  | ''      | ''     | 'T2H-GAVEN' | 'AOS_AO6402A.pdf' | ''            | ''     | ''  | ''         | ''      | '20141008'
 'NTGS4141NT1G' | 'SMLF'    | 'IC'     | 'BAM41410005'(!) = 'End of Design'  | 'Comp-Approve'   | 'BAM41410005' |'TSOP6XB'| 'TRANS MOS NTGS4141NT1G(30V,7.0A,TSOP6)' | 'ONS'   | 'NTGS4141NT1G' | 'EP(V1)'     | 'EP(V1)'  | 'IC'  | ''      | ''     | 'T2H-GAVEN' | 'ONS_NTGS4141NT1G_REV0.pdf' | ''            | ''     | ''  | ''         | ''      | '20141104'
 'NTGS4141NT1G' | 'SMLF'    | 'EMPTY'  | 'BAM41410005'(!) = 'End of Design'  | 'Comp-Approve'   | 'BAM41410005' |'TSOP6XB'| 'TRANS MOS NTGS4141NT1G(30V,7.0A,TSOP6)' | 'ONS'   | 'NTGS4141NT1G' | 'EP(V1)'     | 'EP(V1)'  | 'IC'  | ''      | ''     | 'T2H-GAVEN' | 'ONS_NTGS4141NT1G_REV0.pdf' | ''            | ''     | ''  | ''         | ''      | '20141104'

END_PART

END.

